# T6G (Grand Teton) — schematic netlist excerpt (pin names and nets, part order shuffled) for the footprints in the layout excerpt that follows; sources: Cadence DE-HDL packaged netlist, KiCad conversion of 04192023_DAF0TMB3IC0_F0TG_MB_C_brd_V02_OCP.brd

R1473  Q_RES  4.7K 5% EMPTY  pkg 0201LF  page 287 : A = P1V8_CPU0_RT_1D ; B = JTAG_TCK_RT_CPU0_P1
R3533  Q_RES  33.2 1% CHIP  pkg 0402LF  page 148 : A = SMB_E1S_3V3AUX_ISO_SCL_R ; B = SMB_E1S_3V3AUX_ISO_SCL
R9019  Q_RES  0 5% CHIP  pkg 0402LF  page 245 : A = PRSNT_CABLE_GPU_A1_ISO_N ; B = PRSNT_CABLE_GPU_A1_ISO_R1_N

(kicad_pcb
	(version 20260206)
	(generator "pcbnew")
	(generator_version "10.0")
	(general
		(thickness 1.6)
		(legacy_teardrops no)
	)
	(paper "A4")
	(title_block
		(title "04192023_DAF0TMB3IC0_F0TG_MB_C_brd_V02_OCP.brd")
		(comment 1 "Grand Teton / footprints 721-723 of 8354")
	)
	(layers
		(0 "F.Cu" signal "TOP")
		(4 "In1.Cu" signal "GND")
		(6 "In2.Cu" signal "IN1")
		(8 "In3.Cu" signal "GND1")
		(10 "In4.Cu" signal "IN2")
		(12 "In5.Cu" signal "GND2")
		(14 "In6.Cu" signal "IN3")
		(16 "In7.Cu" signal "GND3")
		(18 "In8.Cu" signal "VCC")
		(20 "In9.Cu" signal "VCC1")
		(22 "In10.Cu" signal "GND4")
		(24 "In11.Cu" signal "IN4")
		(26 "In12.Cu" signal "GND5")
		(28 "In13.Cu" signal "IN5")
		(30 "In14.Cu" signal "GND6")
		(32 "In15.Cu" signal "IN6")
		(34 "In16.Cu" signal "GND7")
		(2 "B.Cu" signal "BOTTOM")
		(9 "F.Adhes" user "F.Adhesive")
		(11 "B.Adhes" user "B.Adhesive")
		(13 "F.Paste" user "Package Geometry/Pastemask Top")
		(15 "B.Paste" user "Package Geometry/Pastemask Bottom")
		(5 "F.SilkS" user "Ref Des/Silkscreen Top")
		(7 "B.SilkS" user "Ref Des/Silkscreen Bottom")
		(1 "F.Mask" user "Board Geometry/Soldermask Top")
		(3 "B.Mask" user "Board Geometry/Soldermask Bottom")
		(17 "Dwgs.User" user "User.Drawings")
		(19 "Cmts.User" user "User.Comments")
		(21 "Eco1.User" user "User.Eco1")
		(23 "Eco2.User" user "User.Eco2")
		(25 "Edge.Cuts" user "Board Geometry/Outline")
		(27 "Margin" user)
		(31 "F.CrtYd" user "Package Geometry/Place Bound Top")
		(29 "B.CrtYd" user "Package Geometry/Place Bound Bottom")
		(35 "F.Fab" user "Ref Des/Assembly Top")
		(33 "B.Fab" user "Ref Des/Assembly Bottom")
	)
	(footprint ""
		(layer "F.Cu")
		(at 223.70288 -43.525948)
		(property "Reference" "R3533"
			(at 0 0 0)
			(layer "F.SilkS")
			(hide yes)
			(effects
				(font
					(size 1.27 1.27)
				)
			)
		)
		(property "Value" ""
			(at 0 0 0)
			(layer "F.Fab")
			(effects
				(font
					(size 1.27 1.27)
				)
			)
		)
		(duplicate_pad_numbers_are_jumpers no)
		(fp_line
			(start -0.7874 -0.4064)
			(end 0.7874 -0.4064)
			(stroke
				(width 0.1524)
				(type default)
			)
			(layer "F.SilkS")
		)
		(fp_line
			(start -0.7874 0.4064)
			(end -0.7874 -0.4064)
			(stroke
				(width 0.1524)
				(type default)
			)
			(layer "F.SilkS")
		)
		(fp_line
			(start 0.7874 -0.4064)
			(end 0.7874 0.4064)
			(stroke
				(width 0.1524)
				(type default)
			)
			(layer "F.SilkS")
		)
		(fp_line
			(start 0.7874 0.4064)
			(end -0.7874 0.4064)
			(stroke
				(width 0.1524)
				(type default)
			)
			(layer "F.SilkS")
		)
		(fp_line
			(start -0.67945 -0.305054)
			(end -0.12065 -0.305054)
			(stroke
				(width 0.1)
				(type default)
			)
			(layer "F.Fab")
		)
		(fp_line
			(start -0.67945 0.3048)
			(end -0.67945 -0.305054)
			(stroke
				(width 0.1)
				(type default)
			)
			(layer "F.Fab")
		)
		(fp_line
			(start -0.12065 -0.305054)
			(end -0.12065 -0.2794)
			(stroke
				(width 0.1)
				(type default)
			)
			(layer "F.Fab")
		)
		(fp_line
			(start -0.12065 -0.2794)
			(end 0.12065 -0.2794)
			(stroke
				(width 0.1)
				(type default)
			)
			(layer "F.Fab")
		)
		(fp_line
			(start -0.12065 0.2794)
			(end -0.12065 0.3048)
			(stroke
				(width 0.1)
				(type default)
			)
			(layer "F.Fab")
		)
		(fp_line
			(start -0.12065 0.3048)
			(end -0.67945 0.3048)
			(stroke
				(width 0.1)
				(type default)
			)
			(layer "F.Fab")
		)
		(fp_line
			(start 0.120396 0.2794)
			(end -0.12065 0.2794)
			(stroke
				(width 0.1)
				(type default)
			)
			(layer "F.Fab")
		)
		(fp_line
			(start 0.120396 0.3048)
			(end 0.120396 0.2794)
			(stroke
				(width 0.1)
				(type default)
			)
			(layer "F.Fab")
		)
		(fp_line
			(start 0.12065 -0.3048)
			(end 0.67945 -0.3048)
			(stroke
				(width 0.1)
				(type default)
			)
			(layer "F.Fab")
		)
		(fp_line
			(start 0.12065 -0.2794)
			(end 0.12065 -0.3048)
			(stroke
				(width 0.1)
				(type default)
			)
			(layer "F.Fab")
		)
		(fp_line
			(start 0.67945 -0.3048)
			(end 0.67945 0.3048)
			(stroke
				(width 0.1)
				(type default)
			)
			(layer "F.Fab")
		)
		(fp_line
			(start 0.67945 0.3048)
			(end 0.120396 0.3048)
			(stroke
				(width 0.1)
				(type default)
			)
			(layer "F.Fab")
		)
		(pad "1" smd circle
			(at -0.40005 0)
			(size 0 0)
			(layers "F.Cu" "F.Mask" "F.Paste")
			(net "SMB_E1S_3V3AUX_ISO_SCL_R")
		)
		(pad "2" smd circle
			(at 0.40005 0)
			(size 0 0)
			(layers "F.Cu" "F.Mask" "F.Paste")
			(net "SMB_E1S_3V3AUX_ISO_SCL")
		)
	)
	(footprint ""
		(layer "F.Cu")
		(at 183.364886 -427.449234 -90)
		(property "Reference" "R9019"
			(at 0 0 270)
			(layer "F.SilkS")
			(hide yes)
			(effects
				(font
					(size 1.27 1.27)
				)
			)
		)
		(property "Value" ""
			(at 0 0 270)
			(layer "F.Fab")
			(effects
				(font
					(size 1.27 1.27)
				)
			)
		)
		(duplicate_pad_numbers_are_jumpers no)
		(fp_line
			(start -0.7874 0.4064)
			(end -0.7874 -0.4064)
			(stroke
				(width 0.1524)
				(type default)
			)
			(layer "F.SilkS")
		)
		(fp_line
			(start 0.7874 0.4064)
			(end -0.7874 0.4064)
			(stroke
				(width 0.1524)
				(type default)
			)
			(layer "F.SilkS")
		)
		(fp_line
			(start -0.7874 -0.4064)
			(end 0.7874 -0.4064)
			(stroke
				(width 0.1524)
				(type default)
			)
			(layer "F.SilkS")
		)
		(fp_line
			(start 0.7874 -0.4064)
			(end 0.7874 0.4064)
			(stroke
				(width 0.1524)
				(type default)
			)
			(layer "F.SilkS")
		)
		(fp_line
			(start -0.67945 0.3048)
			(end -0.67945 -0.305054)
			(stroke
				(width 0.1)
				(type default)
			)
			(layer "F.Fab")
		)
		(fp_line
			(start -0.12065 0.3048)
			(end -0.67945 0.3048)
			(stroke
				(width 0.1)
				(type default)
			)
			(layer "F.Fab")
		)
		(fp_line
			(start 0.120396 0.3048)
			(end 0.120396 0.2794)
			(stroke
				(width 0.1)
				(type default)
			)
			(layer "F.Fab")
		)
		(fp_line
			(start 0.67945 0.3048)
			(end 0.120396 0.3048)
			(stroke
				(width 0.1)
				(type default)
			)
			(layer "F.Fab")
		)
		(fp_line
			(start -0.12065 0.2794)
			(end -0.12065 0.3048)
			(stroke
				(width 0.1)
				(type default)
			)
			(layer "F.Fab")
		)
		(fp_line
			(start 0.120396 0.2794)
			(end -0.12065 0.2794)
			(stroke
				(width 0.1)
				(type default)
			)
			(layer "F.Fab")
		)
		(fp_line
			(start -0.12065 -0.2794)
			(end 0.12065 -0.2794)
			(stroke
				(width 0.1)
				(type default)
			)
			(layer "F.Fab")
		)
		(fp_line
			(start 0.12065 -0.2794)
			(end 0.12065 -0.3048)
			(stroke
				(width 0.1)
				(type default)
			)
			(layer "F.Fab")
		)
		(fp_line
			(start 0.12065 -0.3048)
			(end 0.67945 -0.3048)
			(stroke
				(width 0.1)
				(type default)
			)
			(layer "F.Fab")
		)
		(fp_line
			(start 0.67945 -0.3048)
			(end 0.67945 0.3048)
			(stroke
				(width 0.1)
				(type default)
			)
			(layer "F.Fab")
		)
		(fp_line
			(start -0.67945 -0.305054)
			(end -0.12065 -0.305054)
			(stroke
				(width 0.1)
				(type default)
			)
			(layer "F.Fab")
		)
		(fp_line
			(start -0.12065 -0.305054)
			(end -0.12065 -0.2794)
			(stroke
				(width 0.1)
				(type default)
			)
			(layer "F.Fab")
		)
		(pad "1" smd circle
			(at -0.40005 0 270)
			(size 0 0)
			(layers "F.Cu" "F.Mask" "F.Paste")
			(net "PRSNT_CABLE_GPU_A1_ISO_N")
		)
		(pad "2" smd circle
			(at 0.40005 0 270)
			(size 0 0)
			(layers "F.Cu" "F.Mask" "F.Paste")
			(net "PRSNT_CABLE_GPU_A1_ISO_R1_N")
		)
	)
	(footprint ""
		(layer "F.Cu")
		(at 353.9236 -407.8732 90)
		(property "Reference" "R1473"
			(at 0 0 90)
			(layer "F.SilkS")
			(hide yes)
			(effects
				(font
					(size 1.27 1.27)
				)
			)
		)
		(property "Value" ""
			(at 0 0 90)
			(layer "F.Fab")
			(effects
				(font
					(size 1.27 1.27)
				)
			)
		)
		(duplicate_pad_numbers_are_jumpers no)
		(fp_line
			(start 0.32512 -0.175006)
			(end 0.32512 0.175006)
			(stroke
				(width 0.1)
				(type default)
			)
			(layer "F.Fab")
		)
		(fp_line
			(start -0.32512 -0.175006)
			(end 0.32512 -0.175006)
			(stroke
				(width 0.1)
				(type default)
			)
			(layer "F.Fab")
		)
		(fp_line
			(start 0.32512 0.175006)
			(end -0.32512 0.175006)
			(stroke
				(width 0.1)
				(type default)
			)
			(layer "F.Fab")
		)
		(fp_line
			(start -0.32512 0.175006)
			(end -0.32512 -0.175006)
			(stroke
				(width 0.1)
				(type default)
			)
			(layer "F.Fab")
		)
		(pad "1" smd rect
			(at -0.2667 0 90)
			(size 0.3048 0.381)
			(layers "F.Cu" "F.Mask" "F.Paste")
			(net "P1V8_CPU0_RT_1D")
		)
		(pad "2" smd rect
			(at 0.2667 0 270)
			(size 0.3048 0.381)
			(layers "F.Cu" "F.Mask" "F.Paste")
			(net "JTAG_TCK_RT_CPU0_P1")
		)
	)
)
